(kicad_pcb
	(version 20260206)
	(generator "pcbnew")
	(generator_version "10.0")
	(general
		(thickness 1.6)
		(legacy_teardrops no)
	)
	(paper "A4")
	(title_block
		(title "Bryce Canyon_R.DPB_16317-1_OCP.brd")
		(comment 1 "Bryce Canyon / footprints 623-627 of 2099")
	)
	(layers
		(0 "F.Cu" signal "TOP")
		(4 "In1.Cu" signal "L2GND")
		(6 "In2.Cu" signal "L3")
		(8 "In3.Cu" signal "L4VCC")
		(10 "In4.Cu" signal "L5VCC")
		(12 "In5.Cu" signal "L6")
		(14 "In6.Cu" signal "L7GND")
		(2 "B.Cu" signal "BOTTOM")
		(9 "F.Adhes" user "F.Adhesive")
		(11 "B.Adhes" user "B.Adhesive")
		(13 "F.Paste" user "Package Geometry/Pastemask Top")
		(15 "B.Paste" user "Package Geometry/Pastemask Bottom")
		(5 "F.SilkS" user "Ref Des/Silkscreen Top")
		(7 "B.SilkS" user "Ref Des/Silkscreen Bottom")
		(1 "F.Mask" user "Board Geometry/Soldermask Top")
		(3 "B.Mask" user "Board Geometry/Soldermask Bottom")
		(17 "Dwgs.User" user "User.Drawings")
		(19 "Cmts.User" user "User.Comments")
		(21 "Eco1.User" user "User.Eco1")
		(23 "Eco2.User" user "User.Eco2")
		(25 "Edge.Cuts" user "Board Geometry/Outline")
		(27 "Margin" user)
		(31 "F.CrtYd" user "Package Geometry/Place Bound Top")
		(29 "B.CrtYd" user "Package Geometry/Place Bound Bottom")
		(35 "F.Fab" user "Ref Des/Assembly Top")
		(33 "B.Fab" user "Ref Des/Assembly Bottom")
	)
	(footprint ""
		(layer "F.Cu")
		(at 206.62138 -241.66322 180)
		(property "Reference" "U5"
			(at 0 0 180)
			(layer "F.SilkS")
			(hide yes)
			(effects
				(font
					(size 1.27 1.27)
				)
			)
		)
		(property "Value" "TCA9555PWR-GP"
			(at 0 -6.9342 180)
			(unlocked yes)
			(layer "F.Fab")
			(hide yes)
			(effects
				(font
					(size 1.016 1.016)
					(thickness 0.1524)
				)
			)
		)
		(property "Device Type" "TSOIC24H48"
			(at 0 -8.5852 180)
			(unlocked yes)
			(layer "F.Fab")
			(hide yes)
			(effects
				(font
					(size 1.016 1.016)
					(thickness 0.1524)
				)
			)
		)
		(duplicate_pad_numbers_are_jumpers no)
		(fp_line
			(start 3.81 1.397)
			(end -4.2291 1.397)
			(stroke
				(width 0.1524)
				(type default)
			)
			(layer "F.SilkS")
		)
		(fp_line
			(start 3.81 -1.397)
			(end 3.81 1.397)
			(stroke
				(width 0.1524)
				(type default)
			)
			(layer "F.SilkS")
		)
		(fp_line
			(start -3.429 0)
			(end -4.2291 0.8001)
			(stroke
				(width 0.1524)
				(type default)
			)
			(layer "F.SilkS")
		)
		(fp_line
			(start -4.22656 3.81)
			(end -4.2291 1.397)
			(stroke
				(width 0.508)
				(type default)
			)
			(layer "F.SilkS")
		)
		(fp_line
			(start -4.2291 3.937)
			(end -4.2291 -1.397)
			(stroke
				(width 0.1524)
				(type default)
			)
			(layer "F.SilkS")
		)
		(fp_line
			(start -4.2291 -0.8001)
			(end -3.429 0)
			(stroke
				(width 0.1524)
				(type default)
			)
			(layer "F.SilkS")
		)
		(fp_line
			(start -4.2291 -1.397)
			(end 3.81 -1.397)
			(stroke
				(width 0.1524)
				(type default)
			)
			(layer "F.SilkS")
		)
		(fp_poly
			(pts
				(xy -3.90652 -1.8542) (xy 3.90652 -1.8542) (xy 3.90652 1.8542) (xy -3.90652 1.8542)
			)
			(stroke
				(width 0)
				(type default)
			)
			(fill yes)
			(layer "F.SilkS")
		)
		(fp_poly
			(pts
				(xy -4.2164 3.81) (xy 4.2164 3.81) (xy 4.22656 -3.81) (xy -4.2164 -3.81)
			)
			(stroke
				(width 0)
				(type default)
			)
			(fill no)
			(layer "F.CrtYd")
		)
		(fp_poly
			(pts
				(xy -4.22656 -3.81) (xy 4.22656 -3.81) (xy 4.22656 3.81) (xy -4.22656 3.81)
			)
			(stroke
				(width 0)
				(type default)
			)
			(fill no)
			(layer "F.Fab")
		)
		(pad "1" smd rect
			(at -3.57632 2.8194 180)
			(size 0.3556 1.524)
			(layers "F.Cu" "F.Mask" "F.Paste")
			(net "IO_EXP4_INT_N")
		)
		(pad "2" smd rect
			(at -2.92608 2.8194 180)
			(size 0.3556 1.524)
			(layers "F.Cu" "F.Mask" "F.Paste")
			(net "IO_EXP4_A1")
		)
		(pad "3" smd rect
			(at -2.27584 2.8194 180)
			(size 0.3556 1.524)
			(layers "F.Cu" "F.Mask" "F.Paste")
			(net "IO_EXP4_A2")
		)
		(pad "4" smd rect
			(at -1.6256 2.8194 180)
			(size 0.3556 1.524)
			(layers "F.Cu" "F.Mask" "F.Paste")
			(net "DRIVE_B_0_INS")
		)
		(pad "5" smd rect
			(at -0.97536 2.8194 180)
			(size 0.3556 1.524)
			(layers "F.Cu" "F.Mask" "F.Paste")
			(net "DRIVE_B_1_INS")
		)
		(pad "6" smd rect
			(at -0.32512 2.8194 180)
			(size 0.3556 1.524)
			(layers "F.Cu" "F.Mask" "F.Paste")
			(net "DRIVE_B_2_INS")
		)
		(pad "7" smd rect
			(at 0.32512 2.8194 180)
			(size 0.3556 1.524)
			(layers "F.Cu" "F.Mask" "F.Paste")
			(net "DRIVE_B_3_INS")
		)
		(pad "8" smd rect
			(at 0.97536 2.8194 180)
			(size 0.3556 1.524)
			(layers "F.Cu" "F.Mask" "F.Paste")
			(net "DRIVE_B_4_INS")
		)
		(pad "9" smd rect
			(at 1.6256 2.8194 180)
			(size 0.3556 1.524)
			(layers "F.Cu" "F.Mask" "F.Paste")
			(net "DRIVE_B_5_INS")
		)
		(pad "10" smd rect
			(at 2.27584 2.8194 180)
			(size 0.3556 1.524)
			(layers "F.Cu" "F.Mask" "F.Paste")
			(net "DRIVE_B_6_INS")
		)
		(pad "11" smd rect
			(at 2.92608 2.8194 180)
			(size 0.3556 1.524)
			(layers "F.Cu" "F.Mask" "F.Paste")
			(net "DRIVE_B_7_INS")
		)
		(pad "12" smd rect
			(at 3.57632 2.8194 180)
			(size 0.3556 1.524)
			(layers "F.Cu" "F.Mask" "F.Paste")
			(net "GND")
		)
		(pad "13" smd rect
			(at 3.57632 -2.8194 180)
			(size 0.3556 1.524)
			(layers "F.Cu" "F.Mask" "F.Paste")
			(net "DRIVE_B_8_INS")
		)
		(pad "14" smd rect
			(at 2.92608 -2.8194 180)
			(size 0.3556 1.524)
			(layers "F.Cu" "F.Mask" "F.Paste")
			(net "DRIVE_B_9_INS")
		)
		(pad "15" smd rect
			(at 2.27584 -2.8194 180)
			(size 0.3556 1.524)
			(layers "F.Cu" "F.Mask" "F.Paste")
			(net "DRIVE_B_10_INS")
		)
		(pad "16" smd rect
			(at 1.6256 -2.8194 180)
			(size 0.3556 1.524)
			(layers "F.Cu" "F.Mask" "F.Paste")
			(net "DRIVE_B_11_INS")
		)
		(pad "17" smd rect
			(at 0.97536 -2.8194 180)
			(size 0.3556 1.524)
			(layers "F.Cu" "F.Mask" "F.Paste")
			(net "DRIVE_B_12_INS")
		)
		(pad "18" smd rect
			(at 0.32512 -2.8194 180)
			(size 0.3556 1.524)
			(layers "F.Cu" "F.Mask" "F.Paste")
			(net "DRIVE_B_13_INS")
		)
		(pad "19" smd rect
			(at -0.32512 -2.8194 180)
			(size 0.3556 1.524)
			(layers "F.Cu" "F.Mask" "F.Paste")
			(net "DRIVE_B_14_INS")
		)
		(pad "20" smd rect
			(at -0.97536 -2.8194 180)
			(size 0.3556 1.524)
			(layers "F.Cu" "F.Mask" "F.Paste")
			(net "DRIVE_B_15_INS")
		)
		(pad "21" smd rect
			(at -1.6256 -2.8194 180)
			(size 0.3556 1.524)
			(layers "F.Cu" "F.Mask" "F.Paste")
			(net "IO_EXP4_A0")
		)
		(pad "22" smd rect
			(at -2.27584 -2.8194 180)
			(size 0.3556 1.524)
			(layers "F.Cu" "F.Mask" "F.Paste")
			(net "IO_EXP4_SCL")
		)
		(pad "23" smd rect
			(at -2.92608 -2.8194 180)
			(size 0.3556 1.524)
			(layers "F.Cu" "F.Mask" "F.Paste")
			(net "IO_EXP4_SDA")
		)
		(pad "24" smd rect
			(at -3.57632 -2.8194 180)
			(size 0.3556 1.524)
			(layers "F.Cu" "F.Mask" "F.Paste")
			(net "P3V3_STBY_B")
		)
	)
	(footprint ""
		(layer "F.Cu")
		(at 41.679368 -213.590378 90)
		(property "Reference" "Q244"
			(at 0 0 90)
			(layer "F.SilkS")
			(hide yes)
			(effects
				(font
					(size 1.27 1.27)
				)
			)
		)
		(property "Value" "SSM3K324R-GP"
			(at 0.127 -8.9662 90)
			(unlocked yes)
			(layer "F.Fab")
			(hide yes)
			(effects
				(font
					(size 1.016 1.016)
					(thickness 0.1524)
				)
			)
		)
		(property "Device Type" "SOT23DGS2D4H35"
			(at 0.127 -10.4902 90)
			(unlocked yes)
			(layer "F.Fab")
			(hide yes)
			(effects
				(font
					(size 1.016 1.016)
					(thickness 0.1524)
				)
			)
		)
		(duplicate_pad_numbers_are_jumpers no)
		(fp_line
			(start 1.651 -1.778)
			(end -1.651 -1.778)
			(stroke
				(width 0.1524)
				(type default)
			)
			(layer "F.SilkS")
		)
		(fp_line
			(start -1.651 -1.778)
			(end -1.651 1.778)
			(stroke
				(width 0.1524)
				(type default)
			)
			(layer "F.SilkS")
		)
		(fp_line
			(start 1.651 1.778)
			(end 1.651 -1.778)
			(stroke
				(width 0.1524)
				(type default)
			)
			(layer "F.SilkS")
		)
		(fp_line
			(start -1.651 1.778)
			(end 1.651 1.778)
			(stroke
				(width 0.1524)
				(type default)
			)
			(layer "F.SilkS")
		)
		(fp_poly
			(pts
				(xy -1.778 1.8796) (xy -1.778 -1.8796) (xy 1.778 -1.8796) (xy 1.778 1.8796)
			)
			(stroke
				(width 0)
				(type default)
			)
			(fill no)
			(layer "F.CrtYd")
		)
		(fp_poly
			(pts
				(xy -1.778 1.8796) (xy -1.778 -1.8796) (xy 1.778 -1.8796) (xy 1.778 1.8796)
			)
			(stroke
				(width 0)
				(type default)
			)
			(fill no)
			(layer "F.Fab")
		)
		(pad "D" smd custom
			(at 0 -0.9525 90)
			(size 0.1905 0.1905)
			(layers "F.Cu" "F.Mask" "F.Paste")
			(net "DRV_ACT_1_N")
			(options
				(clearance outline)
				(anchor circle)
			)
			(primitives
				(gr_poly
					(pts
						(arc
							(start -0.1778 0.5715)
							(mid -0.321484 0.511984)
							(end -0.381 0.3683)
						)
						(arc
							(start -0.381 -0.3683)
							(mid -0.321484 -0.511984)
							(end -0.1778 -0.5715)
						)
						(arc
							(start 0.1778 -0.5715)
							(mid 0.321484 -0.511984)
							(end 0.381 -0.3683)
						)
						(arc
							(start 0.381 0.3683)
							(mid 0.321484 0.511984)
							(end 0.1778 0.5715)
						)
					)
					(width 0)
					(fill yes)
				)
			)
		)
		(pad "G" smd custom
			(at -0.98425 0.9525 90)
			(size 0.1905 0.1905)
			(layers "F.Cu" "F.Mask" "F.Paste")
			(net "DRIVE_B_1_ACT")
			(options
				(clearance outline)
				(anchor circle)
			)
			(primitives
				(gr_poly
					(pts
						(arc
							(start -0.1778 0.5715)
							(mid -0.321484 0.511984)
							(end -0.381 0.3683)
						)
						(arc
							(start -0.381 -0.3683)
							(mid -0.321484 -0.511984)
							(end -0.1778 -0.5715)
						)
						(arc
							(start 0.1778 -0.5715)
							(mid 0.321484 -0.511984)
							(end 0.381 -0.3683)
						)
						(arc
							(start 0.381 0.3683)
							(mid 0.321484 0.511984)
							(end 0.1778 0.5715)
						)
					)
					(width 0)
					(fill yes)
				)
			)
		)
		(pad "S" smd custom
			(at 0.98425 0.9525 90)
			(size 0.1905 0.1905)
			(layers "F.Cu" "F.Mask" "F.Paste")
			(net "GND")
			(options
				(clearance outline)
				(anchor circle)
			)
			(primitives
				(gr_poly
					(pts
						(arc
							(start -0.1778 0.5715)
							(mid -0.321484 0.511984)
							(end -0.381 0.3683)
						)
						(arc
							(start -0.381 -0.3683)
							(mid -0.321484 -0.511984)
							(end -0.1778 -0.5715)
						)
						(arc
							(start 0.1778 -0.5715)
							(mid 0.321484 -0.511984)
							(end 0.381 -0.3683)
						)
						(arc
							(start 0.381 0.3683)
							(mid 0.321484 0.511984)
							(end 0.1778 0.5715)
						)
					)
					(width 0)
					(fill yes)
				)
			)
		)
	)
	(footprint ""
		(layer "F.Cu")
		(at 54.483 -134.493 90)
		(property "Reference" "R381"
			(at 0 0 90)
			(layer "F.SilkS")
			(hide yes)
			(effects
				(font
					(size 1.27 1.27)
				)
			)
		)
		(property "Value" "4K7R2F-GP"
			(at 0.064008 -3.993896 90)
			(unlocked yes)
			(layer "F.Fab")
			(hide yes)
			(effects
				(font
					(size 1.016 1.016)
					(thickness 0.1524)
				)
			)
		)
		(property "Device Type" "R402H16"
			(at 0.064008 -5.517896 90)
			(unlocked yes)
			(layer "F.Fab")
			(hide yes)
			(effects
				(font
					(size 1.016 1.016)
					(thickness 0.1524)
				)
			)
		)
		(duplicate_pad_numbers_are_jumpers no)
		(fp_line
			(start 0.508 -0.9398)
			(end -0.508 -0.9398)
			(stroke
				(width 0.1524)
				(type default)
			)
			(layer "F.SilkS")
		)
		(fp_line
			(start -0.508 -0.9398)
			(end -0.508 0.9398)
			(stroke
				(width 0.1524)
				(type default)
			)
			(layer "F.SilkS")
		)
		(fp_rect
			(start -0.508 0.9398)
			(end 0.508 -0.9398)
			(stroke
				(width 0)
				(type default)
			)
			(fill no)
			(layer "F.CrtYd")
		)
		(fp_rect
			(start -0.508 0.9398)
			(end 0.508 -0.9398)
			(stroke
				(width 0)
				(type default)
			)
			(fill no)
			(layer "F.Fab")
		)
		(pad "1" smd custom
			(at 0 -0.4445 90)
			(size 0.1397 0.1397)
			(layers "F.Cu" "F.Mask" "F.Paste")
			(net "SW_PWR_R_HDD13")
			(options
				(clearance outline)
				(anchor circle)
			)
			(primitives
				(gr_poly
					(pts
						(arc
							(start -0.1778 -0.2794)
							(mid -0.249642 -0.249642)
							(end -0.2794 -0.1778)
						)
						(arc
							(start -0.2794 0.1778)
							(mid -0.249642 0.249642)
							(end -0.1778 0.2794)
						)
						(arc
							(start 0.1778 0.2794)
							(mid 0.249642 0.249642)
							(end 0.2794 0.1778)
						)
						(arc
							(start 0.2794 -0.1778)
							(mid 0.249642 -0.249642)
							(end 0.1778 -0.2794)
						)
					)
					(width 0)
					(fill yes)
				)
			)
		)
		(pad "2" smd custom
			(at 0 0.4445 90)
			(size 0.1397 0.1397)
			(layers "F.Cu" "F.Mask" "F.Paste")
			(net "GND")
			(options
				(clearance outline)
				(anchor circle)
			)
			(primitives
				(gr_poly
					(pts
						(arc
							(start -0.1778 -0.2794)
							(mid -0.249642 -0.249642)
							(end -0.2794 -0.1778)
						)
						(arc
							(start -0.2794 0.1778)
							(mid -0.249642 0.249642)
							(end -0.1778 0.2794)
						)
						(arc
							(start 0.1778 0.2794)
							(mid 0.249642 0.249642)
							(end 0.2794 0.1778)
						)
						(arc
							(start 0.2794 -0.1778)
							(mid 0.249642 -0.249642)
							(end 0.1778 -0.2794)
						)
					)
					(width 0)
					(fill yes)
				)
			)
		)
	)
	(footprint ""
		(layer "F.Cu")
		(at 457.003404 -370.8908 180)
		(property "Reference" "U52"
			(at 0 0 180)
			(layer "F.SilkS")
			(hide yes)
			(effects
				(font
					(size 1.27 1.27)
				)
			)
		)
		(property "Value" "SN74LVC1G08DCKR-GP"
			(at -2.3368 -8.6868 180)
			(unlocked yes)
			(layer "F.Fab")
			(hide yes)
			(effects
				(font
					(size 1.016 1.016)
					(thickness 0.1524)
				)
			)
		)
		(property "Device Type" "SC70-5H44"
			(at -2.3114 -10.414 180)
			(unlocked yes)
			(layer "F.Fab")
			(hide yes)
			(effects
				(font
					(size 1.016 1.016)
					(thickness 0.1524)
				)
			)
		)
		(duplicate_pad_numbers_are_jumpers no)
		(fp_line
			(start 1.3843 -1.8034)
			(end 1.3843 -1.1176)
			(stroke
				(width 0.3302)
				(type default)
			)
			(layer "F.SilkS")
		)
		(fp_line
			(start 1.27 1.7018)
			(end -1.27 1.7018)
			(stroke
				(width 0.1524)
				(type default)
			)
			(layer "F.SilkS")
		)
		(fp_line
			(start 1.27 -1.7018)
			(end 1.27 1.7018)
			(stroke
				(width 0.1524)
				(type default)
			)
			(layer "F.SilkS")
		)
		(fp_line
			(start 0.6604 -1.8034)
			(end 1.3843 -1.8034)
			(stroke
				(width 0.3302)
				(type default)
			)
			(layer "F.SilkS")
		)
		(fp_line
			(start -1.27 1.7018)
			(end -1.27 -1.7018)
			(stroke
				(width 0.1524)
				(type default)
			)
			(layer "F.SilkS")
		)
		(fp_line
			(start -1.27 -1.7018)
			(end 1.27 -1.7018)
			(stroke
				(width 0.1524)
				(type default)
			)
			(layer "F.SilkS")
		)
		(fp_rect
			(start -1.524 1.9558)
			(end 1.524 -1.9558)
			(stroke
				(width 0)
				(type default)
			)
			(fill no)
			(layer "F.CrtYd")
		)
		(fp_poly
			(pts
				(xy -1.524 -1.9558) (xy 1.524 -1.9558) (xy 1.524 1.9558) (xy -1.524 1.9558)
			)
			(stroke
				(width 0)
				(type default)
			)
			(fill no)
			(layer "F.Fab")
		)
		(pad "1" smd rect
			(at 0.65024 -0.8255 180)
			(size 0.4064 1.2192)
			(layers "F.Cu" "F.Mask" "F.Paste")
			(net "RDPB_FAN_LED3")
		)
		(pad "2" smd rect
			(at 0 -0.8255 180)
			(size 0.4064 1.2192)
			(layers "F.Cu" "F.Mask" "F.Paste")
			(net "FDPB_FAN_LED3")
		)
		(pad "3" smd rect
			(at -0.65024 -0.8255 180)
			(size 0.4064 1.2192)
			(layers "F.Cu" "F.Mask" "F.Paste")
			(net "GND")
		)
		(pad "4" smd rect
			(at -0.65024 0.8255 180)
			(size 0.4064 1.2192)
			(layers "F.Cu" "F.Mask" "F.Paste")
			(net "FAN_LED3")
		)
		(pad "5" smd rect
			(at 0.65024 0.8255 180)
			(size 0.4064 1.2192)
			(layers "F.Cu" "F.Mask" "F.Paste")
			(net "P3V3_IN")
		)
	)
	(footprint ""
		(layer "F.Cu")
		(at 406.554178 -214.757 180)
		(property "Reference" "Q228"
			(at 0 0 180)
			(layer "F.SilkS")
			(hide yes)
			(effects
				(font
					(size 1.27 1.27)
				)
			)
		)
		(property "Value" "2N7002K-2-GP"
			(at 0.127 -8.9662 180)
			(unlocked yes)
			(layer "F.Fab")
			(hide yes)
			(effects
				(font
					(size 1.016 1.016)
					(thickness 0.1524)
				)
			)
		)
		(property "Device Type" "SOT23DGS2D4H44"
			(at 0.127 -10.4902 180)
			(unlocked yes)
			(layer "F.Fab")
			(hide yes)
			(effects
				(font
					(size 1.016 1.016)
					(thickness 0.1524)
				)
			)
		)
		(duplicate_pad_numbers_are_jumpers no)
		(fp_line
			(start 1.651 1.778)
			(end 1.651 -1.778)
			(stroke
				(width 0.1524)
				(type default)
			)
			(layer "F.SilkS")
		)
		(fp_line
			(start 1.651 -1.778)
			(end -1.651 -1.778)
			(stroke
				(width 0.1524)
				(type default)
			)
			(layer "F.SilkS")
		)
		(fp_line
			(start -1.651 1.778)
			(end 1.651 1.778)
			(stroke
				(width 0.1524)
				(type default)
			)
			(layer "F.SilkS")
		)
		(fp_line
			(start -1.651 -1.778)
			(end -1.651 1.778)
			(stroke
				(width 0.1524)
				(type default)
			)
			(layer "F.SilkS")
		)
		(fp_poly
			(pts
				(xy -1.778 1.8796) (xy -1.778 -1.8796) (xy 1.778 -1.8796) (xy 1.778 1.8796)
			)
			(stroke
				(width 0)
				(type default)
			)
			(fill no)
			(layer "F.CrtYd")
		)
		(fp_poly
			(pts
				(xy -1.778 1.8796) (xy -1.778 -1.8796) (xy 1.778 -1.8796) (xy 1.778 1.8796)
			)
			(stroke
				(width 0)
				(type default)
			)
			(fill no)
			(layer "F.Fab")
		)
		(pad "D" smd custom
			(at 0 -0.9525 180)
			(size 0.1905 0.1905)
			(layers "F.Cu" "F.Mask" "F.Paste")
			(net "FLT_HDD9_N")
			(options
				(clearance outline)
				(anchor circle)
			)
			(primitives
				(gr_poly
					(pts
						(arc
							(start -0.1778 0.5715)
							(mid -0.321484 0.511984)
							(end -0.381 0.3683)
						)
						(arc
							(start -0.381 -0.3683)
							(mid -0.321484 -0.511984)
							(end -0.1778 -0.5715)
						)
						(arc
							(start 0.1778 -0.5715)
							(mid 0.321484 -0.511984)
							(end 0.381 -0.3683)
						)
						(arc
							(start 0.381 0.3683)
							(mid 0.321484 0.511984)
							(end 0.1778 0.5715)
						)
					)
					(width 0)
					(fill yes)
				)
			)
		)
		(pad "G" smd custom
			(at -0.98425 0.9525 180)
			(size 0.1905 0.1905)
			(layers "F.Cu" "F.Mask" "F.Paste")
			(net "DRIVE_B_9_FLT_LED")
			(options
				(clearance outline)
				(anchor circle)
			)
			(primitives
				(gr_poly
					(pts
						(arc
							(start -0.1778 0.5715)
							(mid -0.321484 0.511984)
							(end -0.381 0.3683)
						)
						(arc
							(start -0.381 -0.3683)
							(mid -0.321484 -0.511984)
							(end -0.1778 -0.5715)
						)
						(arc
							(start 0.1778 -0.5715)
							(mid 0.321484 -0.511984)
							(end 0.381 -0.3683)
						)
						(arc
							(start 0.381 0.3683)
							(mid 0.321484 0.511984)
							(end 0.1778 0.5715)
						)
					)
					(width 0)
					(fill yes)
				)
			)
		)
		(pad "S" smd custom
			(at 0.98425 0.9525 180)
			(size 0.1905 0.1905)
			(layers "F.Cu" "F.Mask" "F.Paste")
			(net "GND")
			(options
				(clearance outline)
				(anchor circle)
			)
			(primitives
				(gr_poly
					(pts
						(arc
							(start -0.1778 0.5715)
							(mid -0.321484 0.511984)
							(end -0.381 0.3683)
						)
						(arc
							(start -0.381 -0.3683)
							(mid -0.321484 -0.511984)
							(end -0.1778 -0.5715)
						)
						(arc
							(start 0.1778 -0.5715)
							(mid 0.321484 -0.511984)
							(end 0.381 -0.3683)
						)
						(arc
							(start 0.381 0.3683)
							(mid 0.321484 0.511984)
							(end 0.1778 0.5715)
						)
					)
					(width 0)
					(fill yes)
				)
			)
		)
	)
)
